FILE_TYPE = CONNECTIVITY;
{Allegro Design Entry HDL 17.4-2019 S026 (4007227) 1/17/2022}
"PAGE_NUMBER" = 381;
0"NC";
1"P5E_CPU0_P0_TX_C_DP<7:0>";
2"P5E_CPU0_P0_TX_C_DP<15:8>";
3"P5E_CPU0_P0_TX_C_DN<15:8>";
4"P5E_CPU0_P0_TX_C_DN<7:0>";
5"P5E_CPU0_P0_TX_C_DP<13>";
6"P5E_CPU0_P0_TX_C_DN<13>";
7"P5E_CPU0_P0_TX_C_DP<14>";
8"P5E_CPU0_P0_TX_C_DP<7>";
9"P5E_CPU0_P0_TX_C_DN<6>";
10"P5E_CPU0_P0_TX_C_DP<6>";
11"P5E_CPU0_P0_TX_C_DN<4>";
12"P5E_CPU0_P0_TX_C_DN<2>";
13"P5E_CPU0_P0_TX_C_DN<3>";
14"P5E_CPU0_P0_TX_C_DN<1>";
15"P5E_CPU0_P0_TX_C_DN<7>";
16"P5E_CPU0_P0_TX_C_DN<5>";
17"P5E_CPU0_P0_TX_C_DN<0>";
18"P5E_CPU0_P0_TX_C_DP<5>";
19"P5E_CPU0_P0_TX_C_DP<11>";
20"P5E_CPU0_P0_TX_C_DN<11>";
21"P5E_CPU0_P0_TX_C_DN<15>";
22"P5E_CPU0_P0_TX_C_DP<15>";
23"P5E_CPU0_P0_TX_C_DP<2>";
24"P5E_CPU0_P0_TX_C_DP<3>";
25"P5E_CPU0_P0_TX_C_DP<1>";
26"P5E_CPU0_P0_TX_C_DP<0>";
27"P5E_CPU0_P0_TX_C_DN<10>";
28"P5E_CPU0_P0_TX_C_DN<9>";
29"P5E_CPU0_P0_TX_C_DN<12>";
30"P5E_CPU0_P0_TX_C_DN<14>";
31"P5E_CPU0_P0_TX_C_DN<8>";
32"P5E_CPU0_P0_TX_C_DP<9>";
33"P5E_CPU0_P0_TX_C_DP<10>";
34"P5E_CPU0_P0_TX_C_DP<12>";
35"P5E_CPU0_P0_TX_C_DP<8>";
36"P5E_CPU0_P0_TX_C_DP<4>";
%"TAP"
"1","(-6975,4725)","0","standard","I10";
;
CDS_LIB"standard"
BODY_TYPE"PLUMBING"
HDL_TAP"TRUE";
"B \NAC \NWC"3;
"S \NAC"
BN"13"6;
%"TAP"
"1","(-6975,5175)","0","standard","I11";
;
CDS_LIB"standard"
BODY_TYPE"PLUMBING"
HDL_TAP"TRUE";
"B \NAC \NWC"3;
"S \NAC"
BN"14"30;
%"TAP"
"1","(-6975,5525)","0","standard","I12";
;
CDS_LIB"standard"
BODY_TYPE"PLUMBING"
HDL_TAP"TRUE";
"B \NAC \NWC"3;
"S \NAC"
BN"15"21;
%"TAP"
"1","(-6775,2975)","0","standard","I13";
;
CDS_LIB"standard"
BODY_TYPE"PLUMBING"
HDL_TAP"TRUE";
"B \NAC \NWC"2;
"S \NAC"
BN"8"35;
%"TAP"
"1","(-6775,3325)","0","standard","I14";
;
CDS_LIB"standard"
BODY_TYPE"PLUMBING"
HDL_TAP"TRUE";
"B \NAC \NWC"2;
"S \NAC"
BN"9"32;
%"TAP"
"1","(-6775,3675)","0","standard","I15";
;
CDS_LIB"standard"
BODY_TYPE"PLUMBING"
HDL_TAP"TRUE";
"B \NAC \NWC"2;
"S \NAC"
BN"10"33;
%"TAP"
"1","(-6775,4025)","0","standard","I16";
;
CDS_LIB"standard"
BODY_TYPE"PLUMBING"
HDL_TAP"TRUE";
"B \NAC \NWC"2;
"S \NAC"
BN"11"19;
%"TAP"
"1","(-6775,4375)","0","standard","I17";
;
CDS_LIB"standard"
BODY_TYPE"PLUMBING"
HDL_TAP"TRUE";
"B \NAC \NWC"2;
"S \NAC"
BN"12"34;
%"TAP"
"1","(-6775,4825)","0","standard","I18";
;
CDS_LIB"standard"
BODY_TYPE"PLUMBING"
HDL_TAP"TRUE";
"B \NAC \NWC"2;
"S \NAC"
BN"13"5;
%"TAP"
"1","(-6775,5075)","0","standard","I19";
;
CDS_LIB"standard"
BODY_TYPE"PLUMBING"
HDL_TAP"TRUE";
"B \NAC \NWC"2;
"S \NAC"
BN"14"7;
%"TAP"
"1","(-6775,5425)","0","standard","I20";
;
CDS_LIB"standard"
BODY_TYPE"PLUMBING"
HDL_TAP"TRUE";
"B \NAC \NWC"2;
"S \NAC"
BN"15"22;
%"TAP"
"1","(-2150,3975)","0","standard","I23";
;
CDS_LIB"standard"
BODY_TYPE"PLUMBING"
HDL_TAP"TRUE";
"B \NAC \NWC"1;
"S \NAC"
BN"3"24;
%"TAP"
"1","(-2350,3725)","0","standard","I24";
;
CDS_LIB"standard"
BODY_TYPE"PLUMBING"
HDL_TAP"TRUE";
"B \NAC \NWC"4;
"S \NAC"
BN"2"12;
%"TAP"
"1","(-2150,5375)","0","standard","I27";
;
CDS_LIB"standard"
BODY_TYPE"PLUMBING"
HDL_TAP"TRUE";
"B \NAC \NWC"1;
"S \NAC"
BN"7"8;
%"TAP"
"1","(-2350,5475)","0","standard","I28";
;
CDS_LIB"standard"
BODY_TYPE"PLUMBING"
HDL_TAP"TRUE";
"B \NAC \NWC"4;
"S \NAC"
BN"7"15;
%"TAP"
"1","(-2350,5125)","0","standard","I29";
;
CDS_LIB"standard"
BODY_TYPE"PLUMBING"
HDL_TAP"TRUE";
"B \NAC \NWC"4;
"S \NAC"
BN"6"9;
%"PT5161LRS"
"8","(-8000,4275)","0","pure_quanta","I3";
;
LOCATION"U6010"
$SEC"8"
CDS_SEC"8"
MATERIAL"IC"
VALUE"PT5161LRS"
PART_TYPE"SMLF"
NEEDS_NO_SIZE"TRUE"
CDS_LMAN_SYM_OUTLINE"-350,1450,300,-1400"
CDS_LIB"pure_quanta"
PART_NUMBER"AJ051610U03";
"B_PERN7"
$PN"CD35"35;
"B_PERP7"
$PN"CB34"31;
"B_PERN6"
$PN"BU35"32;
"B_PERP6"
$PN"BR34"28;
"B_PERN5"
$PN"BK35"33;
"B_PERP5"
$PN"BH34"27;
"B_PERN4"
$PN"BC35"19;
"B_PERP4"
$PN"BA34"20;
"B_PERN3"
$PN"AT35"34;
"B_PERP3"
$PN"AP34"29;
"B_PERN2"
$PN"AJ35"6;
"B_PERP2"
$PN"AG34"5;
"B_PERN1"
$PN"AB35"7;
"B_PERP1"
$PN"Y34"30;
"B_PERN0"
$PN"R35"22;
"B_PERP0"
$PN"N34"21;
%"TAP"
"1","(-2150,5025)","0","standard","I30";
;
CDS_LIB"standard"
BODY_TYPE"PLUMBING"
HDL_TAP"TRUE";
"B \NAC \NWC"1;
"S \NAC"
BN"6"10;
%"TAP"
"1","(-2150,4675)","0","standard","I31";
;
CDS_LIB"standard"
BODY_TYPE"PLUMBING"
HDL_TAP"TRUE";
"B \NAC \NWC"1;
"S \NAC"
BN"5"18;
%"TAP"
"1","(-2350,4775)","0","standard","I32";
;
CDS_LIB"standard"
BODY_TYPE"PLUMBING"
HDL_TAP"TRUE";
"B \NAC \NWC"4;
"S \NAC"
BN"5"16;
%"TAP"
"1","(-2150,4325)","0","standard","I33";
;
CDS_LIB"standard"
BODY_TYPE"PLUMBING"
HDL_TAP"TRUE";
"B \NAC \NWC"1;
"S \NAC"
BN"4"36;
%"TAP"
"1","(-2350,4425)","0","standard","I34";
;
CDS_LIB"standard"
BODY_TYPE"PLUMBING"
HDL_TAP"TRUE";
"B \NAC \NWC"4;
"S \NAC"
BN"4"11;
%"TAP"
"1","(-2350,4075)","0","standard","I35";
;
CDS_LIB"standard"
BODY_TYPE"PLUMBING"
HDL_TAP"TRUE";
"B \NAC \NWC"4;
"S \NAC"
BN"3"13;
%"TAP"
"1","(-2150,3625)","0","standard","I36";
;
CDS_LIB"standard"
BODY_TYPE"PLUMBING"
HDL_TAP"TRUE";
"B \NAC \NWC"1;
"S \NAC"
BN"2"23;
%"TAP"
"1","(-2150,3375)","0","standard","I37";
;
CDS_LIB"standard"
BODY_TYPE"PLUMBING"
HDL_TAP"TRUE";
"B \NAC \NWC"1;
"S \NAC"
BN"1"25;
%"TAP"
"1","(-2350,3275)","0","standard","I38";
;
CDS_LIB"standard"
BODY_TYPE"PLUMBING"
HDL_TAP"TRUE";
"B \NAC \NWC"4;
"S \NAC"
BN"1"14;
%"TAP"
"1","(-2350,3025)","0","standard","I39";
;
CDS_LIB"standard"
BODY_TYPE"PLUMBING"
HDL_TAP"TRUE";
"B \NAC \NWC"4;
"S \NAC"
BN"0"17;
%"PT5161LRS"
"9","(-3375,4225)","0","pure_quanta","I4";
;
LOCATION"U6010"
$SEC"9"
CDS_SEC"9"
PART_TYPE"SMLF"
MATERIAL"IC"
VALUE"PT5161LRS"
CDS_LIB"pure_quanta"
CDS_LMAN_SYM_OUTLINE"-350,1450,300,-1400"
NEEDS_NO_SIZE"TRUE"
PART_NUMBER"AJ051610U03";
"B_PERN15"
$PN"EY35"26;
"B_PERP15"
$PN"EV34"17;
"B_PERN14"
$PN"EN35"14;
"B_PERP14"
$PN"EL34"25;
"B_PERN13"
$PN"EF35"23;
"B_PERP13"
$PN"ED34"12;
"B_PERN12"
$PN"DW35"24;
"B_PERP12"
$PN"DU34"13;
"B_PERN11"
$PN"DM35"36;
"B_PERP11"
$PN"DK34"11;
"B_PERN10"
$PN"DE35"18;
"B_PERP10"
$PN"DC34"16;
"B_PERN9"
$PN"CV35"10;
"B_PERP9"
$PN"CT34"9;
"B_PERN8"
$PN"CL35"8;
"B_PERP8"
$PN"CJ34"15;
%"TAP"
"1","(-2150,2925)","0","standard","I40";
;
CDS_LIB"standard"
BODY_TYPE"PLUMBING"
HDL_TAP"TRUE";
"B \NAC \NWC"1;
"S \NAC"
BN"0"26;
%"TAP"
"1","(-6975,3075)","0","standard","I5";
;
CDS_LIB"standard"
BODY_TYPE"PLUMBING"
HDL_TAP"TRUE";
"B \NAC \NWC"3;
"S \NAC"
BN"8"31;
%"TAP"
"1","(-6975,3425)","0","standard","I6";
;
CDS_LIB"standard"
BODY_TYPE"PLUMBING"
HDL_TAP"TRUE";
"B \NAC \NWC"3;
"S \NAC"
BN"9"28;
%"TAP"
"1","(-6975,3775)","0","standard","I7";
;
CDS_LIB"standard"
BODY_TYPE"PLUMBING"
HDL_TAP"TRUE";
"B \NAC \NWC"3;
"S \NAC"
BN"10"27;
%"TAP"
"1","(-6975,4125)","0","standard","I8";
;
CDS_LIB"standard"
BODY_TYPE"PLUMBING"
HDL_TAP"TRUE";
"B \NAC \NWC"3;
"S \NAC"
BN"11"20;
%"TAP"
"1","(-6975,4475)","0","standard","I9";
;
CDS_LIB"standard"
BODY_TYPE"PLUMBING"
HDL_TAP"TRUE";
"B \NAC \NWC"3;
"S \NAC"
BN"12"29;
END.
